# T6G (Grand Teton) — schematic netlist excerpt (pin names and nets, part order shuffled) for the footprints in the layout excerpt that follows; sources: Cadence DE-HDL packaged netlist, KiCad conversion of 04192023_DAF0TMB3IC0_F0TG_MB_C_brd_V02_OCP.brd

R6793  Q_RES  0 5% CHIP  pkg 0402LF  page 81 : A = RST_RT_CPU1_P2_RESET_R_N ; B = RST_RT_CPU1_P2_RESET_R2_N
R8034  Q_RES  0 5% CHIP  pkg 0402LF  page 153 : A = ESPI_CPU0_ALERT_R1_N ; B = ESPI_CPU0_ALERT_N

(kicad_pcb
	(version 20260206)
	(generator "pcbnew")
	(generator_version "10.0")
	(general
		(thickness 1.6)
		(legacy_teardrops no)
	)
	(paper "A4")
	(title_block
		(title "04192023_DAF0TMB3IC0_F0TG_MB_C_brd_V02_OCP.brd")
		(comment 1 "Grand Teton / footprints 7747-7748 of 8354")
	)
	(layers
		(0 "F.Cu" signal "TOP")
		(4 "In1.Cu" signal "GND")
		(6 "In2.Cu" signal "IN1")
		(8 "In3.Cu" signal "GND1")
		(10 "In4.Cu" signal "IN2")
		(12 "In5.Cu" signal "GND2")
		(14 "In6.Cu" signal "IN3")
		(16 "In7.Cu" signal "GND3")
		(18 "In8.Cu" signal "VCC")
		(20 "In9.Cu" signal "VCC1")
		(22 "In10.Cu" signal "GND4")
		(24 "In11.Cu" signal "IN4")
		(26 "In12.Cu" signal "GND5")
		(28 "In13.Cu" signal "IN5")
		(30 "In14.Cu" signal "GND6")
		(32 "In15.Cu" signal "IN6")
		(34 "In16.Cu" signal "GND7")
		(2 "B.Cu" signal "BOTTOM")
		(9 "F.Adhes" user "F.Adhesive")
		(11 "B.Adhes" user "B.Adhesive")
		(13 "F.Paste" user "Package Geometry/Pastemask Top")
		(15 "B.Paste" user "Package Geometry/Pastemask Bottom")
		(5 "F.SilkS" user "Ref Des/Silkscreen Top")
		(7 "B.SilkS" user "Ref Des/Silkscreen Bottom")
		(1 "F.Mask" user "Board Geometry/Soldermask Top")
		(3 "B.Mask" user "Board Geometry/Soldermask Bottom")
		(17 "Dwgs.User" user "User.Drawings")
		(19 "Cmts.User" user "User.Comments")
		(21 "Eco1.User" user "User.Eco1")
		(23 "Eco2.User" user "User.Eco2")
		(25 "Edge.Cuts" user "Board Geometry/Outline")
		(27 "Margin" user)
		(31 "F.CrtYd" user "Package Geometry/Place Bound Top")
		(29 "B.CrtYd" user "Package Geometry/Place Bound Bottom")
		(35 "F.Fab" user "Ref Des/Assembly Top")
		(33 "B.Fab" user "Ref Des/Assembly Bottom")
	)
	(footprint ""
		(layer "B.Cu")
		(at 182.468774 -133.843014 90)
		(property "Reference" "R6793"
			(at 0 0 90)
			(layer "B.SilkS")
			(hide yes)
			(effects
				(font
					(size 1.27 1.27)
				)
				(justify mirror)
			)
		)
		(property "Value" ""
			(at 0 0 90)
			(layer "B.Fab")
			(effects
				(font
					(size 1.27 1.27)
				)
				(justify mirror)
			)
		)
		(duplicate_pad_numbers_are_jumpers no)
		(fp_line
			(start 0.7874 -0.4064)
			(end -0.7874 -0.4064)
			(stroke
				(width 0.1524)
				(type default)
			)
			(layer "B.SilkS")
		)
		(fp_line
			(start -0.7874 -0.4064)
			(end -0.7874 0.4064)
			(stroke
				(width 0.1524)
				(type default)
			)
			(layer "B.SilkS")
		)
		(fp_line
			(start 0.7874 0.4064)
			(end 0.7874 -0.4064)
			(stroke
				(width 0.1524)
				(type default)
			)
			(layer "B.SilkS")
		)
		(fp_line
			(start -0.7874 0.4064)
			(end 0.7874 0.4064)
			(stroke
				(width 0.1524)
				(type default)
			)
			(layer "B.SilkS")
		)
		(fp_line
			(start 0.67945 -0.305054)
			(end 0.12065 -0.305054)
			(stroke
				(width 0.1)
				(type default)
			)
			(layer "B.Fab")
		)
		(fp_line
			(start 0.12065 -0.305054)
			(end 0.12065 -0.2794)
			(stroke
				(width 0.1)
				(type default)
			)
			(layer "B.Fab")
		)
		(fp_line
			(start -0.12065 -0.3048)
			(end -0.67945 -0.3048)
			(stroke
				(width 0.1)
				(type default)
			)
			(layer "B.Fab")
		)
		(fp_line
			(start -0.67945 -0.3048)
			(end -0.67945 0.3048)
			(stroke
				(width 0.1)
				(type default)
			)
			(layer "B.Fab")
		)
		(fp_line
			(start 0.12065 -0.2794)
			(end -0.12065 -0.2794)
			(stroke
				(width 0.1)
				(type default)
			)
			(layer "B.Fab")
		)
		(fp_line
			(start -0.12065 -0.2794)
			(end -0.12065 -0.3048)
			(stroke
				(width 0.1)
				(type default)
			)
			(layer "B.Fab")
		)
		(fp_line
			(start 0.12065 0.2794)
			(end 0.12065 0.3048)
			(stroke
				(width 0.1)
				(type default)
			)
			(layer "B.Fab")
		)
		(fp_line
			(start -0.120396 0.2794)
			(end 0.12065 0.2794)
			(stroke
				(width 0.1)
				(type default)
			)
			(layer "B.Fab")
		)
		(fp_line
			(start 0.67945 0.3048)
			(end 0.67945 -0.305054)
			(stroke
				(width 0.1)
				(type default)
			)
			(layer "B.Fab")
		)
		(fp_line
			(start 0.12065 0.3048)
			(end 0.67945 0.3048)
			(stroke
				(width 0.1)
				(type default)
			)
			(layer "B.Fab")
		)
		(fp_line
			(start -0.120396 0.3048)
			(end -0.120396 0.2794)
			(stroke
				(width 0.1)
				(type default)
			)
			(layer "B.Fab")
		)
		(fp_line
			(start -0.67945 0.3048)
			(end -0.120396 0.3048)
			(stroke
				(width 0.1)
				(type default)
			)
			(layer "B.Fab")
		)
		(pad "1" smd circle
			(at 0.40005 0 270)
			(size 0 0)
			(layers "B.Cu" "B.Mask" "B.Paste")
			(net "RST_RT_CPU1_P2_RESET_R_N")
		)
		(pad "2" smd circle
			(at -0.40005 0 270)
			(size 0 0)
			(layers "B.Cu" "B.Mask" "B.Paste")
			(net "RST_RT_CPU1_P2_RESET_R2_N")
		)
	)
	(footprint ""
		(layer "B.Cu")
		(at 185.680858 -147.837144 180)
		(property "Reference" "R8034"
			(at 0 0 0)
			(layer "B.SilkS")
			(hide yes)
			(effects
				(font
					(size 1.27 1.27)
				)
				(justify mirror)
			)
		)
		(property "Value" ""
			(at 0 0 0)
			(layer "B.Fab")
			(effects
				(font
					(size 1.27 1.27)
				)
				(justify mirror)
			)
		)
		(duplicate_pad_numbers_are_jumpers no)
		(fp_line
			(start 0.7874 0.4064)
			(end 0.7874 -0.4064)
			(stroke
				(width 0.1524)
				(type default)
			)
			(layer "B.SilkS")
		)
		(fp_line
			(start 0.7874 -0.4064)
			(end -0.7874 -0.4064)
			(stroke
				(width 0.1524)
				(type default)
			)
			(layer "B.SilkS")
		)
		(fp_line
			(start -0.7874 0.4064)
			(end 0.7874 0.4064)
			(stroke
				(width 0.1524)
				(type default)
			)
			(layer "B.SilkS")
		)
		(fp_line
			(start -0.7874 -0.4064)
			(end -0.7874 0.4064)
			(stroke
				(width 0.1524)
				(type default)
			)
			(layer "B.SilkS")
		)
		(fp_line
			(start 0.67945 0.3048)
			(end 0.67945 -0.305054)
			(stroke
				(width 0.1)
				(type default)
			)
			(layer "B.Fab")
		)
		(fp_line
			(start 0.67945 -0.305054)
			(end 0.12065 -0.305054)
			(stroke
				(width 0.1)
				(type default)
			)
			(layer "B.Fab")
		)
		(fp_line
			(start 0.12065 0.3048)
			(end 0.67945 0.3048)
			(stroke
				(width 0.1)
				(type default)
			)
			(layer "B.Fab")
		)
		(fp_line
			(start 0.12065 0.2794)
			(end 0.12065 0.3048)
			(stroke
				(width 0.1)
				(type default)
			)
			(layer "B.Fab")
		)
		(fp_line
			(start 0.12065 -0.2794)
			(end -0.12065 -0.2794)
			(stroke
				(width 0.1)
				(type default)
			)
			(layer "B.Fab")
		)
		(fp_line
			(start 0.12065 -0.305054)
			(end 0.12065 -0.2794)
			(stroke
				(width 0.1)
				(type default)
			)
			(layer "B.Fab")
		)
		(fp_line
			(start -0.120396 0.3048)
			(end -0.120396 0.2794)
			(stroke
				(width 0.1)
				(type default)
			)
			(layer "B.Fab")
		)
		(fp_line
			(start -0.120396 0.2794)
			(end 0.12065 0.2794)
			(stroke
				(width 0.1)
				(type default)
			)
			(layer "B.Fab")
		)
		(fp_line
			(start -0.12065 -0.2794)
			(end -0.12065 -0.3048)
			(stroke
				(width 0.1)
				(type default)
			)
			(layer "B.Fab")
		)
		(fp_line
			(start -0.12065 -0.3048)
			(end -0.67945 -0.3048)
			(stroke
				(width 0.1)
				(type default)
			)
			(layer "B.Fab")
		)
		(fp_line
			(start -0.67945 0.3048)
			(end -0.120396 0.3048)
			(stroke
				(width 0.1)
				(type default)
			)
			(layer "B.Fab")
		)
		(fp_line
			(start -0.67945 -0.3048)
			(end -0.67945 0.3048)
			(stroke
				(width 0.1)
				(type default)
			)
			(layer "B.Fab")
		)
		(pad "1" smd circle
			(at 0.40005 0)
			(size 0 0)
			(layers "B.Cu" "B.Mask" "B.Paste")
			(net "ESPI_CPU0_ALERT_R1_N")
		)
		(pad "2" smd circle
			(at -0.40005 0)
			(size 0 0)
			(layers "B.Cu" "B.Mask" "B.Paste")
			(net "ESPI_CPU0_ALERT_N")
		)
	)
)
